# BASEBOARD_FAB2 (Tioga Pass) — schematic netlist excerpt (pin names and nets, part order shuffled) for the footprints in the layout excerpt that follows; sources: Cadence DE-HDL packaged netlist, KiCad conversion of Wiwynn_Tioga_Pass_MB.brd

J1A2  SCONN288_H44441004  SCONN  pkg PIP  page 85
  \12v\(1)  = P12V_NVDIMM_KLM
  VSS(93)  = GND
  DQ(4)  = M_L_DQ<5>
  VSS(92)  = GND
  DQ(0)  = M_L_DQ<1>
  VSS(91)  = GND
  DQS9P  = M_L_DQS_DP<9>
  DQS9N  = M_L_DQS_DN<9>
  VSS(90)  = GND
  DQ(6)  = M_L_DQ<7>
  VSS(89)  = GND
  DQ(2)  = M_L_DQ<3>
  VSS(88)  = GND
  DQ(12)  = M_L_DQ<13>
  VSS(87)  = GND
  DQ(8)  = M_L_DQ<9>
  VSS(86)  = GND
  DQS10P  = M_L_DQS_DP<10>
  DQS10N  = M_L_DQS_DN<10>
  VSS(85)  = GND
  DQ(14)  = M_L_DQ<15>
  VSS(84)  = GND
  DQ(10)  = M_L_DQ<11>
  VSS(83)  = GND
  DQ(20)  = M_L_DQ<21>
  VSS(82)  = GND
  DQ(16)  = M_L_DQ<17>
  VSS(81)  = GND
  DQS11P  = M_L_DQS_DP<11>
  DQS11N  = M_L_DQS_DN<11>
  VSS(80)  = GND
  DQ(22)  = M_L_DQ<23>
  VSS(79)  = GND
  DQ(18)  = M_L_DQ<19>
  VSS(78)  = GND
  DQ(28)  = M_L_DQ<29>
  VSS(77)  = GND
  DQ(24)  = M_L_DQ<25>
  VSS(76)  = GND
  DQS12P  = M_L_DQS_DP<12>
  DQS12N  = M_L_DQS_DN<12>
  VSS(75)  = GND
  DQ(30)  = M_L_DQ<31>
  VSS(74)  = GND
  DQ(26)  = M_L_DQ<27>
  VSS(73)  = GND
  CB(4)  = M_L_ECC<5>
  VSS(72)  = GND
  CB(0)  = M_L_ECC<1>
  VSS(71)  = GND
  DQS17P  = M_L_DQS_DP<17>
  DQS17N  = M_L_DQS_DN<17>
  VSS(70)  = GND
  CB(6)  = M_L_ECC<7>
  VSS(69)  = GND
  CB(2)  = M_L_ECC<3>
  VSS(68)  = GND
  RESET_N  = M_KLM_RST_N
  VDD(25)  = PVDDQ_KLM
  CKE(0)  = M_L_CKE<0>
  VDD(24)  = PVDDQ_KLM
  ACT_N  = M_L_ACT_N
  BG(0)  = M_L_BG<0>
  VDD(23)  = PVDDQ_KLM
  A12  = M_L_MA<12>
  A9  = M_L_MA<9>
  VDD(22)  = PVDDQ_KLM
  A8  = M_L_MA<8>
  A6  = M_L_MA<6>
  VDD(21)  = PVDDQ_KLM
  A3  = M_L_MA<3>
  A1  = M_L_MA<1>
  VDD(20)  = PVDDQ_KLM
  CK0P  = M_L_CLK_DP<0>
  CK0N  = M_L_CLK_DN<0>
  VDD(19)  = PVDDQ_KLM
  VTT(1)  = PVTT_KLM
  EVENT_N  = FM_DIMM_EVENT_COD_N
  A0  = M_L_MA<0>
  VDD(18)  = PVDDQ_KLM
  BA(0)  = M_L_BA<0>
  A16_RAS_N  = M_L_MA<16>
  VDD(17)  = PVDDQ_KLM
  S0_N  = M_L_CS_N<0>
  VDD(16)  = PVDDQ_KLM
  A15_CAS_N  = M_L_MA<15>
  ODT(0)  = M_L_ODT<0>
  VDD(15)  = PVDDQ_KLM
  S1_N  = M_L_CS_N<1>
  VDD(14)  = PVDDQ_KLM
  ODT(1)  = M_L_ODT<1>
  VDD(13)  = PVDDQ_KLM
  S2_N_C(0)  = M_L_CS_N<2>
  VSS(67)  = GND
  DQ(36)  = M_L_DQ<37>
  VSS(66)  = GND
  DQ(32)  = M_L_DQ<33>
  VSS(65)  = GND
  DQS13P  = M_L_DQS_DP<13>
  DQS13N  = M_L_DQS_DN<13>
  VSS(64)  = GND
  DQ(38)  = M_L_DQ<39>
  VSS(63)  = GND
  DQ(34)  = M_L_DQ<35>
  VSS(62)  = GND
  DQ(44)  = M_L_DQ<45>
  VSS(61)  = GND
  DQ(40)  = M_L_DQ<41>
  VSS(60)  = GND
  DQS14P  = M_L_DQS_DP<14>
  DQS14N  = M_L_DQS_DN<14>
  VSS(59)  = GND
  DQ(46)  = M_L_DQ<47>
  VSS(58)  = GND
  DQ(42)  = M_L_DQ<43>
  VSS(57)  = GND
  DQ(52)  = M_L_DQ<53>
  VSS(56)  = GND
  DQ(48)  = M_L_DQ<49>
  VSS(55)  = GND
  DQS15P  = M_L_DQS_DP<15>
  DQS15N  = M_L_DQS_DN<15>
  VSS(54)  = GND
  DQ(54)  = M_L_DQ<55>
  VSS(53)  = GND
  DQ(50)  = M_L_DQ<51>
  VSS(52)  = GND
  DQ(60)  = M_L_DQ<61>
  VSS(51)  = GND
  DQ(56)  = M_L_DQ<57>
  VSS(50)  = GND
  DQS16P  = M_L_DQS_DP<16>
  DQS16N  = M_L_DQS_DN<16>
  VSS(49)  = GND
  DQ(62)  = M_L_DQ<63>
  VSS(48)  = GND
  DQ(58)  = M_L_DQ<59>
  VSS(47)  = GND
  SA(0)  = GND
  SA(1)  = PVPP_KLM
  SCL  = SMB_DDR_KLM_VPP_SCL
  VPP(4)  = PVPP_KLM
  VPP(3)  = PVPP_KLM
  RFU(2)  = TP_CH_L_DIMM_L0_RFU_2
  \12v\(0)  = P12V_NVDIMM_KLM
  VREFCA  = M_L_VREF
  VSS(46)  = GND
  DQ(5)  = M_L_DQ<4>
  VSS(45)  = GND
  DQ(1)  = M_L_DQ<0>
  VSS(44)  = GND
  DQS0N  = M_L_DQS_DN<0>
  DQS0P  = M_L_DQS_DP<0>
  VSS(43)  = GND
  DQ(7)  = M_L_DQ<6>
  VSS(42)  = GND
  DQ(3)  = M_L_DQ<2>
  VSS(41)  = GND
  DQ(13)  = M_L_DQ<12>
  VSS(40)  = GND
  DQ(9)  = M_L_DQ<8>
  VSS(39)  = GND
  DQS1N  = M_L_DQS_DN<1>
  DQS1P  = M_L_DQS_DP<1>
  VSS(38)  = GND
  DQ(15)  = M_L_DQ<14>
  VSS(37)  = GND
  DQ(11)  = M_L_DQ<10>
  VSS(36)  = GND
  DQ(21)  = M_L_DQ<20>
  VSS(35)  = GND
  DQ(17)  = M_L_DQ<16>
  VSS(34)  = GND
  DQS2N  = M_L_DQS_DN<2>
  DQS2P  = M_L_DQS_DP<2>
  VSS(33)  = GND
  DQ(23)  = M_L_DQ<22>
  VSS(32)  = GND
  DQ(19)  = M_L_DQ<18>
  VSS(31)  = GND
  DQ(29)  = M_L_DQ<28>
  VSS(30)  = GND
  DQ(25)  = M_L_DQ<24>
  VSS(29)  = GND
  DQS3N  = M_L_DQS_DN<3>
  DQS3P  = M_L_DQS_DP<3>
  VSS(28)  = GND
  DQ(31)  = M_L_DQ<30>
  VSS(27)  = GND
  DQ(27)  = M_L_DQ<26>
  VSS(26)  = GND
  CB(5)  = M_L_ECC<4>
  VSS(25)  = GND
  CB(1)  = M_L_ECC<0>
  VSS(24)  = GND
  DQS8N  = M_L_DQS_DN<8>
  DQS8P  = M_L_DQS_DP<8>
  VSS(23)  = GND
  CB(7)  = M_L_ECC<6>
  VSS(22)  = GND
  CB(3)  = M_L_ECC<2>
  VSS(21)  = GND
  CKE(1)  = M_L_CKE<1>
  VDD(12)  = PVDDQ_KLM
  RFU(0)  = TP_CH_L_DIMM_L0_RFU_0
  VDD(11)  = PVDDQ_KLM
  BG(1)  = M_L_BG<1>
  ALERT_N  = M_L_ALERT_N
  VDD(10)  = PVDDQ_KLM
  A11  = M_L_MA<11>
  A7  = M_L_MA<7>
  VDD(9)  = PVDDQ_KLM
  A5  = M_L_MA<5>
  A4  = M_L_MA<4>
  VDD(8)  = PVDDQ_KLM
  A2  = M_L_MA<2>
  VDD(7)  = PVDDQ_KLM
  CK1P  = M_L_CLK_DP<1>
  CK1N  = M_L_CLK_DN<1>
  VDD(6)  = PVDDQ_KLM
  VTT(0)  = PVTT_KLM
  PAR  = M_L_PAR
  VDD(5)  = PVDDQ_KLM
  BA(1)  = M_L_BA<1>
  A10  = M_L_MA<10>
  VDD(4)  = PVDDQ_KLM
  RFU(1)  = TP_CH_L_DIMM_L0_RFU_1
  A14_WE_N  = M_L_MA<14>
  VDD(3)  = PVDDQ_KLM
  SAVE_N_NC  = FM_ADR_COMPLETE_KLM_N
  VDD(2)  = PVDDQ_KLM
  A13  = M_L_MA<13>
  VDD(1)  = PVDDQ_KLM
  A17  = M_L_MA<17>
  C(2)  = M_L_C<2>
  VDD(0)  = PVDDQ_KLM
  S3_N_C(1)  = M_L_CS_N<3>
  SA(2)  = GND
  VSS(20)  = GND
  DQ(37)  = M_L_DQ<36>
  VSS(19)  = GND
  DQ(33)  = M_L_DQ<32>
  VSS(18)  = GND
  DQS4N  = M_L_DQS_DN<4>
  DQS4P  = M_L_DQS_DP<4>
  VSS(17)  = GND
  DQ(39)  = M_L_DQ<38>
  VSS(16)  = GND
  DQ(35)  = M_L_DQ<34>
  VSS(15)  = GND
  DQ(45)  = M_L_DQ<44>
  VSS(14)  = GND
  DQ(41)  = M_L_DQ<40>
  VSS(13)  = GND
  DQS5N  = M_L_DQS_DN<5>
  DQS5P  = M_L_DQS_DP<5>
  VSS(12)  = GND
  DQ(47)  = M_L_DQ<46>
  VSS(11)  = GND
  DQ(43)  = M_L_DQ<42>
  VSS(10)  = GND
  DQ(53)  = M_L_DQ<52>
  VSS(9)  = GND
  DQ(49)  = M_L_DQ<48>
  VSS(8)  = GND
  DQS6N  = M_L_DQS_DN<6>
  DQS6P  = M_L_DQS_DP<6>
  VSS(7)  = GND
  DQ(55)  = M_L_DQ<54>
  VSS(6)  = GND
  DQ(51)  = M_L_DQ<50>
  VSS(5)  = GND
  DQ(61)  = M_L_DQ<60>
  VSS(4)  = GND
  DQ(57)  = M_L_DQ<56>
  VSS(3)  = GND
  DQS7N  = M_L_DQS_DN<7>
  DQS7P  = M_L_DQS_DP<7>
  VSS(2)  = GND
  DQ(63)  = M_L_DQ<62>
  VSS(1)  = GND
  DQ(59)  = M_L_DQ<58>
  VSS(0)  = GND
  VDDSPD  = PVPP_KLM
  SDA  = SMB_DDR_KLM_VPP_SDA
  VPP(1)  = PVPP_KLM
  VPP(0)  = PVPP_KLM
  VPP(2)  = PVPP_KLM

(kicad_pcb
	(version 20260206)
	(generator "pcbnew")
	(generator_version "10.0")
	(general
		(thickness 1.6)
		(legacy_teardrops no)
	)
	(paper "A4")
	(title_block
		(title "Wiwynn_Tioga_Pass_MB.brd")
		(comment 1 "Tioga Pass / footprint 2031 of 4770 (J1A2), pads 102-152 of 291")
	)
	(layers
		(0 "F.Cu" signal "TOP")
		(4 "In1.Cu" signal "L2GND")
		(6 "In2.Cu" signal "L3")
		(8 "In3.Cu" signal "L4GND")
		(10 "In4.Cu" signal "L5")
		(12 "In5.Cu" signal "L6GND")
		(14 "In6.Cu" signal "L7VCC")
		(16 "In7.Cu" signal "L8VCC")
		(18 "In8.Cu" signal "L9GND")
		(20 "In9.Cu" signal "L10")
		(22 "In10.Cu" signal "L11GND")
		(24 "In11.Cu" signal "L12")
		(26 "In12.Cu" signal "L13GND")
		(2 "B.Cu" signal "BOTTOM")
		(9 "F.Adhes" user "F.Adhesive")
		(11 "B.Adhes" user "B.Adhesive")
		(13 "F.Paste" user "Package Geometry/Pastemask Top")
		(15 "B.Paste" user "Package Geometry/Pastemask Bottom")
		(5 "F.SilkS" user "Ref Des/Silkscreen Top")
		(7 "B.SilkS" user "Ref Des/Silkscreen Bottom")
		(1 "F.Mask" user "Board Geometry/Soldermask Top")
		(3 "B.Mask" user "Board Geometry/Soldermask Bottom")
		(17 "Dwgs.User" user "User.Drawings")
		(19 "Cmts.User" user "User.Comments")
		(21 "Eco1.User" user "User.Eco1")
		(23 "Eco2.User" user "User.Eco2")
		(25 "Edge.Cuts" user "Board Geometry/Outline")
		(27 "Margin" user)
		(31 "F.CrtYd" user "Package Geometry/Place Bound Top")
		(29 "B.CrtYd" user "Package Geometry/Place Bound Bottom")
		(35 "F.Fab" user "Ref Des/Assembly Top")
		(33 "B.Fab" user "Ref Des/Assembly Bottom")
	)
	(footprint ""
		(layer "F.Cu")
		(at 29.699458 -142.6718 90)
		(property "Reference" "J1A2"
			(at -2.623312 42.436542 0)
			(unlocked yes)
			(layer "F.SilkS")
			(effects
				(font
					(size 0.7874 0.5842)
					(thickness 0.1524)
				)
				(justify left)
			)
		)
		(property "Value" ""
			(at 0 0 90)
			(layer "F.Fab")
			(effects
				(font
					(size 1.27 1.27)
				)
			)
		)
		(duplicate_pad_numbers_are_jumpers no)
		(pad "99" smd rect
			(at 0 88.399874 90)
			(size 1.8034 0.508)
			(layers "F.Cu" "F.Mask" "F.Paste")
			(net "M_L_DQS_DP<13>")
		)
		(pad "100" smd rect
			(at 0 89.250012 90)
			(size 1.8034 0.508)
			(layers "F.Cu" "F.Mask" "F.Paste")
			(net "M_L_DQS_DN<13>")
		)
		(pad "101" smd rect
			(at 0 90.099896 90)
			(size 1.8034 0.508)
			(layers "F.Cu" "F.Mask" "F.Paste")
			(net "GND")
		)
		(pad "102" smd rect
			(at 0 90.950034 90)
			(size 1.8034 0.508)
			(layers "F.Cu" "F.Mask" "F.Paste")
			(net "M_L_DQ<39>")
		)
		(pad "103" smd rect
			(at 0 91.799918 90)
			(size 1.8034 0.508)
			(layers "F.Cu" "F.Mask" "F.Paste")
			(net "GND")
		)
		(pad "104" smd rect
			(at 0 92.650056 90)
			(size 1.8034 0.508)
			(layers "F.Cu" "F.Mask" "F.Paste")
			(net "M_L_DQ<35>")
		)
		(pad "105" smd rect
			(at 0 93.49994 90)
			(size 1.8034 0.508)
			(layers "F.Cu" "F.Mask" "F.Paste")
			(net "GND")
		)
		(pad "106" smd rect
			(at 0 94.350078 90)
			(size 1.8034 0.508)
			(layers "F.Cu" "F.Mask" "F.Paste")
			(net "M_L_DQ<45>")
		)
		(pad "107" smd rect
			(at 0 95.199962 90)
			(size 1.8034 0.508)
			(layers "F.Cu" "F.Mask" "F.Paste")
			(net "GND")
		)
		(pad "108" smd rect
			(at 0 96.0501 90)
			(size 1.8034 0.508)
			(layers "F.Cu" "F.Mask" "F.Paste")
			(net "M_L_DQ<41>")
		)
		(pad "109" smd rect
			(at 0 96.899984 90)
			(size 1.8034 0.508)
			(layers "F.Cu" "F.Mask" "F.Paste")
			(net "GND")
		)
		(pad "110" smd rect
			(at 0 97.750122 90)
			(size 1.8034 0.508)
			(layers "F.Cu" "F.Mask" "F.Paste")
			(net "M_L_DQS_DP<14>")
		)
		(pad "111" smd rect
			(at 0 98.600006 90)
			(size 1.8034 0.508)
			(layers "F.Cu" "F.Mask" "F.Paste")
			(net "M_L_DQS_DN<14>")
		)
		(pad "112" smd rect
			(at 0 99.44989 90)
			(size 1.8034 0.508)
			(layers "F.Cu" "F.Mask" "F.Paste")
			(net "GND")
		)
		(pad "113" smd rect
			(at 0 100.300028 90)
			(size 1.8034 0.508)
			(layers "F.Cu" "F.Mask" "F.Paste")
			(net "M_L_DQ<47>")
		)
		(pad "114" smd rect
			(at 0 101.149912 90)
			(size 1.8034 0.508)
			(layers "F.Cu" "F.Mask" "F.Paste")
			(net "GND")
		)
		(pad "115" smd rect
			(at 0 102.00005 90)
			(size 1.8034 0.508)
			(layers "F.Cu" "F.Mask" "F.Paste")
			(net "M_L_DQ<43>")
		)
		(pad "116" smd rect
			(at 0 102.849934 90)
			(size 1.8034 0.508)
			(layers "F.Cu" "F.Mask" "F.Paste")
			(net "GND")
		)
		(pad "117" smd rect
			(at 0 103.700072 90)
			(size 1.8034 0.508)
			(layers "F.Cu" "F.Mask" "F.Paste")
			(net "M_L_DQ<53>")
		)
		(pad "118" smd rect
			(at 0 104.549956 90)
			(size 1.8034 0.508)
			(layers "F.Cu" "F.Mask" "F.Paste")
			(net "GND")
		)
		(pad "119" smd rect
			(at 0 105.400094 90)
			(size 1.8034 0.508)
			(layers "F.Cu" "F.Mask" "F.Paste")
			(net "M_L_DQ<49>")
		)
		(pad "120" smd rect
			(at 0 106.249978 90)
			(size 1.8034 0.508)
			(layers "F.Cu" "F.Mask" "F.Paste")
			(net "GND")
		)
		(pad "121" smd rect
			(at 0 107.100116 90)
			(size 1.8034 0.508)
			(layers "F.Cu" "F.Mask" "F.Paste")
			(net "M_L_DQS_DP<15>")
		)
		(pad "122" smd rect
			(at 0 107.95 90)
			(size 1.8034 0.508)
			(layers "F.Cu" "F.Mask" "F.Paste")
			(net "M_L_DQS_DN<15>")
		)
		(pad "123" smd rect
			(at 0 108.799884 90)
			(size 1.8034 0.508)
			(layers "F.Cu" "F.Mask" "F.Paste")
			(net "GND")
		)
		(pad "124" smd rect
			(at 0 109.650022 90)
			(size 1.8034 0.508)
			(layers "F.Cu" "F.Mask" "F.Paste")
			(net "M_L_DQ<55>")
		)
		(pad "125" smd rect
			(at 0 110.499906 90)
			(size 1.8034 0.508)
			(layers "F.Cu" "F.Mask" "F.Paste")
			(net "GND")
		)
		(pad "126" smd rect
			(at 0 111.350044 90)
			(size 1.8034 0.508)
			(layers "F.Cu" "F.Mask" "F.Paste")
			(net "M_L_DQ<51>")
		)
		(pad "127" smd rect
			(at 0 112.199928 90)
			(size 1.8034 0.508)
			(layers "F.Cu" "F.Mask" "F.Paste")
			(net "GND")
		)
		(pad "128" smd rect
			(at 0 113.050066 90)
			(size 1.8034 0.508)
			(layers "F.Cu" "F.Mask" "F.Paste")
			(net "M_L_DQ<61>")
		)
		(pad "129" smd rect
			(at 0 113.89995 90)
			(size 1.8034 0.508)
			(layers "F.Cu" "F.Mask" "F.Paste")
			(net "GND")
		)
		(pad "130" smd rect
			(at 0 114.750088 90)
			(size 1.8034 0.508)
			(layers "F.Cu" "F.Mask" "F.Paste")
			(net "M_L_DQ<57>")
		)
		(pad "131" smd rect
			(at 0 115.599972 90)
			(size 1.8034 0.508)
			(layers "F.Cu" "F.Mask" "F.Paste")
			(net "GND")
		)
		(pad "132" smd rect
			(at 0 116.45011 90)
			(size 1.8034 0.508)
			(layers "F.Cu" "F.Mask" "F.Paste")
			(net "M_L_DQS_DP<16>")
		)
		(pad "133" smd rect
			(at 0 117.299994 90)
			(size 1.8034 0.508)
			(layers "F.Cu" "F.Mask" "F.Paste")
			(net "M_L_DQS_DN<16>")
		)
		(pad "134" smd rect
			(at 0 118.149878 90)
			(size 1.8034 0.508)
			(layers "F.Cu" "F.Mask" "F.Paste")
			(net "GND")
		)
		(pad "135" smd rect
			(at 0 119.000016 90)
			(size 1.8034 0.508)
			(layers "F.Cu" "F.Mask" "F.Paste")
			(net "M_L_DQ<63>")
		)
		(pad "136" smd rect
			(at 0 119.8499 90)
			(size 1.8034 0.508)
			(layers "F.Cu" "F.Mask" "F.Paste")
			(net "GND")
		)
		(pad "137" smd rect
			(at 0 120.700038 90)
			(size 1.8034 0.508)
			(layers "F.Cu" "F.Mask" "F.Paste")
			(net "M_L_DQ<59>")
		)
		(pad "138" smd rect
			(at 0 121.549922 90)
			(size 1.8034 0.508)
			(layers "F.Cu" "F.Mask" "F.Paste")
			(net "GND")
		)
		(pad "139" smd rect
			(at 0 122.40006 90)
			(size 1.8034 0.508)
			(layers "F.Cu" "F.Mask" "F.Paste")
			(net "GND")
		)
		(pad "140" smd rect
			(at 0 123.249944 90)
			(size 1.8034 0.508)
			(layers "F.Cu" "F.Mask" "F.Paste")
			(net "PVPP_KLM")
		)
		(pad "141" smd rect
			(at 0 124.100082 90)
			(size 1.8034 0.508)
			(layers "F.Cu" "F.Mask" "F.Paste")
			(net "SMB_DDR_KLM_VPP_SCL")
		)
		(pad "142" smd rect
			(at 0 124.949966 90)
			(size 1.8034 0.508)
			(layers "F.Cu" "F.Mask" "F.Paste")
			(net "PVPP_KLM")
		)
		(pad "143" smd rect
			(at 0 125.800104 90)
			(size 1.8034 0.508)
			(layers "F.Cu" "F.Mask" "F.Paste")
			(net "PVPP_KLM")
		)
		(pad "144" smd rect
			(at 0 126.649988 90)
			(size 1.8034 0.508)
			(layers "F.Cu" "F.Mask" "F.Paste")
			(net "TP_CH_L_DIMM_L0_RFU_2")
		)
		(pad "145" smd rect
			(at 4.59994 0 90)
			(size 1.8034 0.508)
			(layers "F.Cu" "F.Mask" "F.Paste")
			(net "P12V_NVDIMM_KLM")
		)
		(pad "146" smd rect
			(at 4.59994 0.849884 90)
			(size 1.8034 0.508)
			(layers "F.Cu" "F.Mask" "F.Paste")
			(net "M_L_VREF")
		)
		(pad "147" smd rect
			(at 4.59994 1.700022 90)
			(size 1.8034 0.508)
			(layers "F.Cu" "F.Mask" "F.Paste")
			(net "GND")
		)
		(pad "148" smd rect
			(at 4.59994 2.549906 90)
			(size 1.8034 0.508)
			(layers "F.Cu" "F.Mask" "F.Paste")
			(net "M_L_DQ<4>")
		)
		(pad "149" smd rect
			(at 4.59994 3.400044 90)
			(size 1.8034 0.508)
			(layers "F.Cu" "F.Mask" "F.Paste")
			(net "GND")
		)
	)
)
